#ISCELL
  logical_power bom_note *
  *
#ISCELL
  mstr_misc dns *
  *
#ISCELL
  pure_quanta quanta_title_block_c *
  *
#ISCELL
  logical_power universal_gnd *
  page50_i138
#CELL
  pure_quanta 74lvc1g07gw *
  page50_i151
#CELL
  pure_quanta q_res *
  page50_i152
#ISCELL
  standard offpage *
  page50_i153
#CELL
  pure_quanta q_res *
  page50_i154
#ISCELL
  standard offpage *
  page50_i155
#CELL
  pure_quanta bas70057f *
  page50_i161
#ISCELL
  standard offpage *
  page50_i162
#ISCELL
  logical_power vccaux15 *
  page50_i163
#ISCELL
  logical_power universal_power *
  page50_i164
#CELL
  pure_quanta q_cap *
  page50_i165
#ISCELL
  logical_power universal_gnd *
  page50_i166
#ISCELL
  logical_power universal_gnd *
  page50_i169
#ISCELL
  logical_power universal_gnd *
  page50_i192
#CELL
  pure_quanta sw_pushbutton4p_12_g34_h2 *
  page50_i204
#ISCELL
  logical_power universal_gnd *
  page50_i208
#CELL
  pure_quanta q_res *
  page50_i210
#ISCELL
  logical_power universal_power *
  page50_i211
#CELL
  pure_quanta q_cap *
  page50_i212
#ISCELL
  logical_power universal_gnd *
  page50_i217
#CELL
  pure_quanta mosfet_nch_dual *
  page50_i218
#ISCELL
  standard offpage *
  page50_i219
#ISCELL
  logical_power universal_power *
  page50_i220
#CELL
  pure_quanta q_res *
  page50_i222
#CELL
  pure_quanta q_res *
  page50_i224
#CELL
  pure_quanta q_res *
  page50_i225
#ISCELL
  logical_power universal_gnd *
  page50_i226
#CELL
  pure_quanta 74lvc1g07gw *
  page50_i227
#ISCELL
  standard offpage *
  page50_i230
#ISCELL
  logical_power vccaux15 *
  page50_i231
#CELL
  pure_quanta q_cap *
  page50_i232
#ISCELL
  logical_power universal_gnd *
  page50_i233
#ISCELL
  logical_power vccaux15 *
  page50_i234
#CELL
  pure_quanta q_res *
  page50_i235
#CELL
  pure_quanta q_cap *
  page50_i236
#ISCELL
  logical_power universal_gnd *
  page50_i238
#ISCELL
  logical_power universal_gnd *
  page50_i239
#CELL
  pure_quanta q_res *
  page50_i241
#CELL
  pure_quanta q_res *
  page50_i242
#ISCELL
  standard offpage *
  page50_i243
#CELL
  pure_quanta diode_bidirectional *
  page50_i244
#ISCELL
  logical_power universal_gnd *
  page50_i245
#CELL
  pure_quanta q_cap *
  page50_i246
#ISCELL
  logical_power universal_gnd *
  page50_i247
#CELL
  pure_quanta 74lvc1g07gw *
  page50_i278
#ISCELL
  standard offpage *
  page50_i279
#ISCELL
  logical_power vccaux15 *
  page50_i280
#CELL
  pure_quanta q_cap *
  page50_i281
#ISCELL
  logical_power universal_gnd *
  page50_i282
#ISCELL
  logical_power vccaux15 *
  page50_i283
#CELL
  pure_quanta q_res *
  page50_i284
#CELL
  pure_quanta q_cap *
  page50_i285
#CELL
  pure_quanta q_res *
  page50_i286
#ISCELL
  logical_power universal_gnd *
  page50_i287
#CELL
  pure_quanta sw_pushbutton4p_12_g34_h2 *
  page50_i292
#CELL
  pure_quanta sw_pushbutton4p_12_g34_h2 *
  page50_i293
#CELL
  pure_quanta q_led *
  page50_i294
#CELL
  pure_quanta q_led *
  page50_i295
#ISCELL
  logical_power universal_gnd *
  page50_i30
#ISCELL
  standard offpage *
  page50_i31
#CELL
  pure_quanta q_cap *
  page50_i43
#CELL
  pure_quanta q_cap *
  page50_i44
#ISCELL
  logical_power vccaux15 *
  page50_i45
#ISCELL
  logical_power universal_gnd *
  page50_i46
#ISCELL
  standard offpage *
  page50_i48
#CELL
  pure_quanta 74lvc1g17gw *
  page50_i49
#ISCELL
  logical_power vccaux15 *
  page50_i50
#CELL
  pure_quanta q_cap *
  page50_i51
#ISCELL
  logical_power universal_gnd *
  page50_i52
#CELL
  pure_quanta q_cap *
  page50_i55
#CELL
  pure_quanta q_res *
  page50_i82
#ISCELL
  logical_power vccaux15 *
  page50_i83
#CELL
  pure_quanta q_res *
  page50_i89
#ISCELL
  logical_power vccaux15 *
  page50_i90
